(kicad_pcb
	(version 20260206)
	(generator "pcbnew")
	(generator_version "10.0")
	(general
		(thickness 1.6)
		(legacy_teardrops no)
	)
	(paper "A4")
	(title_block
		(title "baseboard — 13948-1b.1110WZS1818.brd")
		(comment 1 "Honey Badger (Wiwynn) / footprints 2238-2246 of 2523")
	)
	(layers
		(0 "F.Cu" signal "TOP")
		(4 "In1.Cu" signal "L2GND")
		(6 "In2.Cu" signal "L3")
		(8 "In3.Cu" signal "L4VCC")
		(10 "In4.Cu" signal "L5VCC")
		(12 "In5.Cu" signal "L6")
		(14 "In6.Cu" signal "L7GND")
		(2 "B.Cu" signal "BOTTOM")
		(9 "F.Adhes" user "F.Adhesive")
		(11 "B.Adhes" user "B.Adhesive")
		(13 "F.Paste" user "Package Geometry/Pastemask Top")
		(15 "B.Paste" user "Package Geometry/Pastemask Bottom")
		(5 "F.SilkS" user "Ref Des/Silkscreen Top")
		(7 "B.SilkS" user "Ref Des/Silkscreen Bottom")
		(1 "F.Mask" user "Board Geometry/Soldermask Top")
		(3 "B.Mask" user "Board Geometry/Soldermask Bottom")
		(17 "Dwgs.User" user "User.Drawings")
		(19 "Cmts.User" user "User.Comments")
		(21 "Eco1.User" user "User.Eco1")
		(23 "Eco2.User" user "User.Eco2")
		(25 "Edge.Cuts" user "Board Geometry/Outline")
		(27 "Margin" user)
		(31 "F.CrtYd" user "Package Geometry/Place Bound Top")
		(29 "B.CrtYd" user "Package Geometry/Place Bound Bottom")
		(35 "F.Fab" user "Ref Des/Assembly Top")
		(33 "B.Fab" user "Ref Des/Assembly Bottom")
	)
	(footprint ""
		(layer "B.Cu")
		(at 107.982004 -56.165496)
		(property "Reference" "STP153"
			(at 0 0 0)
			(layer "B.SilkS")
			(hide yes)
			(effects
				(font
					(size 1.27 1.27)
				)
				(justify mirror)
			)
		)
		(property "Value" "TPAD28"
			(at -0.0127 -1.8034 0)
			(unlocked yes)
			(layer "B.Fab")
			(hide yes)
			(effects
				(font
					(size 1.016 1.016)
					(thickness 0.1524)
				)
				(justify mirror)
			)
		)
		(property "Device Type" "TPAD28"
			(at -0.0127 -3.3274 0)
			(unlocked yes)
			(layer "B.Fab")
			(hide yes)
			(effects
				(font
					(size 1.016 1.016)
					(thickness 0.1524)
				)
				(justify mirror)
			)
		)
		(duplicate_pad_numbers_are_jumpers no)
		(fp_poly
			(pts
				(arc
					(start 0.3556 0)
					(mid -0.3556 0)
					(end 0.3556 0)
				)
			)
			(stroke
				(width 0)
				(type default)
			)
			(fill no)
			(layer "B.CrtYd")
		)
		(fp_poly
			(pts
				(arc
					(start 0.6096 0)
					(mid -0.6096 0)
					(end 0.6096 0)
				)
			)
			(stroke
				(width 0)
				(type default)
			)
			(fill no)
			(layer "B.Fab")
		)
		(pad "1" smd circle
			(at 0 0 180)
			(size 0.7112 0.7112)
			(layers "B.Cu" "B.Mask" "B.Paste")
			(net "XM_CLE")
		)
	)
	(footprint ""
		(layer "B.Cu")
		(at 99.45116 -31.623)
		(property "Reference" "SC869"
			(at 0 0 0)
			(layer "B.SilkS")
			(hide yes)
			(effects
				(font
					(size 1.27 1.27)
				)
				(justify mirror)
			)
		)
		(property "Value" "SCD22U6D3V1MX-1-GP"
			(at 2.8321 -1.7399 0)
			(unlocked yes)
			(layer "B.Fab")
			(hide yes)
			(effects
				(font
					(size 1.016 1.016)
					(thickness 0.1524)
				)
				(justify mirror)
			)
		)
		(property "Device Type" "C0201H13"
			(at 2.8321 -3.2639 0)
			(unlocked yes)
			(layer "B.Fab")
			(hide yes)
			(effects
				(font
					(size 1.016 1.016)
					(thickness 0.1524)
				)
				(justify mirror)
			)
		)
		(duplicate_pad_numbers_are_jumpers no)
		(fp_rect
			(start 0.2794 0.6477)
			(end -0.2794 -0.6477)
			(stroke
				(width 0)
				(type default)
			)
			(fill no)
			(layer "B.CrtYd")
		)
		(fp_rect
			(start 0.2794 0.6477)
			(end -0.2794 -0.6477)
			(stroke
				(width 0)
				(type default)
			)
			(fill no)
			(layer "B.Fab")
		)
		(pad "1" smd custom
			(at 0 -0.2794 180)
			(size 0.0762 0.0762)
			(layers "B.Cu" "B.Mask" "B.Paste")
			(net "PCIE_SAS_C_CPU_RX_P4")
			(options
				(clearance outline)
				(anchor circle)
			)
			(primitives
				(gr_poly
					(pts
						(arc
							(start 0.1524 0.127)
							(mid 0.137521 0.162921)
							(end 0.1016 0.1778)
						)
						(arc
							(start -0.1016 0.1778)
							(mid -0.137521 0.162921)
							(end -0.1524 0.127)
						)
						(arc
							(start -0.1524 -0.127)
							(mid -0.137521 -0.162921)
							(end -0.1016 -0.1778)
						)
						(arc
							(start 0.1016 -0.1778)
							(mid 0.137521 -0.162921)
							(end 0.1524 -0.127)
						)
					)
					(width 0)
					(fill yes)
				)
			)
		)
		(pad "2" smd custom
			(at 0 0.2794 180)
			(size 0.0762 0.0762)
			(layers "B.Cu" "B.Mask" "B.Paste")
			(net "PCIE_SAS_CPU_RX_P4")
			(options
				(clearance outline)
				(anchor circle)
			)
			(primitives
				(gr_poly
					(pts
						(arc
							(start 0.1524 0.127)
							(mid 0.137521 0.162921)
							(end 0.1016 0.1778)
						)
						(arc
							(start -0.1016 0.1778)
							(mid -0.137521 0.162921)
							(end -0.1524 0.127)
						)
						(arc
							(start -0.1524 -0.127)
							(mid -0.137521 -0.162921)
							(end -0.1016 -0.1778)
						)
						(arc
							(start 0.1016 -0.1778)
							(mid 0.137521 -0.162921)
							(end 0.1524 -0.127)
						)
					)
					(width 0)
					(fill yes)
				)
			)
		)
	)
	(footprint ""
		(layer "B.Cu")
		(at 351.6122 -71.8058)
		(property "Reference" "R342"
			(at 0 0 0)
			(layer "B.SilkS")
			(hide yes)
			(effects
				(font
					(size 1.27 1.27)
				)
				(justify mirror)
			)
		)
		(property "Value" "3K3R2F-2-GP"
			(at -0.064008 -3.993896 0)
			(unlocked yes)
			(layer "B.Fab")
			(hide yes)
			(effects
				(font
					(size 1.016 1.016)
					(thickness 0.1524)
				)
				(justify mirror)
			)
		)
		(property "Device Type" "R402H16"
			(at -0.064008 -5.517896 0)
			(unlocked yes)
			(layer "B.Fab")
			(hide yes)
			(effects
				(font
					(size 1.016 1.016)
					(thickness 0.1524)
				)
				(justify mirror)
			)
		)
		(duplicate_pad_numbers_are_jumpers no)
		(fp_line
			(start -0.508 -0.9398)
			(end 0.508 -0.9398)
			(stroke
				(width 0.1524)
				(type default)
			)
			(layer "B.SilkS")
		)
		(fp_line
			(start 0.508 -0.9398)
			(end 0.508 0.9398)
			(stroke
				(width 0.1524)
				(type default)
			)
			(layer "B.SilkS")
		)
		(fp_rect
			(start 0.508 0.9398)
			(end -0.508 -0.9398)
			(stroke
				(width 0)
				(type default)
			)
			(fill no)
			(layer "B.CrtYd")
		)
		(fp_rect
			(start 0.508 0.9398)
			(end -0.508 -0.9398)
			(stroke
				(width 0)
				(type default)
			)
			(fill no)
			(layer "B.Fab")
		)
		(pad "1" smd custom
			(at 0 -0.4445 180)
			(size 0.1397 0.1397)
			(layers "B.Cu" "B.Mask" "B.Paste")
			(net "P3V3_STBY")
			(options
				(clearance outline)
				(anchor circle)
			)
			(primitives
				(gr_poly
					(pts
						(arc
							(start -0.1778 0.2794)
							(mid -0.249642 0.249642)
							(end -0.2794 0.1778)
						)
						(arc
							(start -0.2794 -0.1778)
							(mid -0.249642 -0.249642)
							(end -0.1778 -0.2794)
						)
						(arc
							(start 0.1778 -0.2794)
							(mid 0.249642 -0.249642)
							(end 0.2794 -0.1778)
						)
						(arc
							(start 0.2794 0.1778)
							(mid 0.249642 0.249642)
							(end 0.1778 0.2794)
						)
					)
					(width 0)
					(fill yes)
				)
			)
		)
		(pad "2" smd custom
			(at 0 0.4445 180)
			(size 0.1397 0.1397)
			(layers "B.Cu" "B.Mask" "B.Paste")
			(net "ROMD0_R")
			(options
				(clearance outline)
				(anchor circle)
			)
			(primitives
				(gr_poly
					(pts
						(arc
							(start -0.1778 0.2794)
							(mid -0.249642 0.249642)
							(end -0.2794 0.1778)
						)
						(arc
							(start -0.2794 -0.1778)
							(mid -0.249642 -0.249642)
							(end -0.1778 -0.2794)
						)
						(arc
							(start 0.1778 -0.2794)
							(mid 0.249642 -0.249642)
							(end 0.2794 -0.1778)
						)
						(arc
							(start 0.2794 0.1778)
							(mid 0.249642 0.249642)
							(end 0.1778 0.2794)
						)
					)
					(width 0)
					(fill yes)
				)
			)
		)
	)
	(footprint ""
		(layer "B.Cu")
		(at 105.918 -239.395)
		(property "Reference" "SR947"
			(at 0 0 0)
			(layer "B.SilkS")
			(hide yes)
			(effects
				(font
					(size 1.27 1.27)
				)
				(justify mirror)
			)
		)
		(property "Value" "4K7R2F-GP"
			(at -0.064008 -3.993896 0)
			(unlocked yes)
			(layer "B.Fab")
			(hide yes)
			(effects
				(font
					(size 1.016 1.016)
					(thickness 0.1524)
				)
				(justify mirror)
			)
		)
		(property "Device Type" "R402H16"
			(at -0.064008 -5.517896 0)
			(unlocked yes)
			(layer "B.Fab")
			(hide yes)
			(effects
				(font
					(size 1.016 1.016)
					(thickness 0.1524)
				)
				(justify mirror)
			)
		)
		(duplicate_pad_numbers_are_jumpers no)
		(fp_line
			(start -0.508 -0.9398)
			(end 0.508 -0.9398)
			(stroke
				(width 0.1524)
				(type default)
			)
			(layer "B.SilkS")
		)
		(fp_line
			(start 0.508 -0.9398)
			(end 0.508 0.9398)
			(stroke
				(width 0.1524)
				(type default)
			)
			(layer "B.SilkS")
		)
		(fp_rect
			(start 0.508 0.9398)
			(end -0.508 -0.9398)
			(stroke
				(width 0)
				(type default)
			)
			(fill no)
			(layer "B.CrtYd")
		)
		(fp_rect
			(start 0.508 0.9398)
			(end -0.508 -0.9398)
			(stroke
				(width 0)
				(type default)
			)
			(fill no)
			(layer "B.Fab")
		)
		(pad "1" smd custom
			(at 0 -0.4445 180)
			(size 0.1397 0.1397)
			(layers "B.Cu" "B.Mask" "B.Paste")
			(net "SAS_FAULT_LED6")
			(options
				(clearance outline)
				(anchor circle)
			)
			(primitives
				(gr_poly
					(pts
						(arc
							(start -0.1778 0.2794)
							(mid -0.249642 0.249642)
							(end -0.2794 0.1778)
						)
						(arc
							(start -0.2794 -0.1778)
							(mid -0.249642 -0.249642)
							(end -0.1778 -0.2794)
						)
						(arc
							(start 0.1778 -0.2794)
							(mid 0.249642 -0.249642)
							(end 0.2794 -0.1778)
						)
						(arc
							(start 0.2794 0.1778)
							(mid 0.249642 0.249642)
							(end 0.1778 0.2794)
						)
					)
					(width 0)
					(fill yes)
				)
			)
		)
		(pad "2" smd custom
			(at 0 0.4445 180)
			(size 0.1397 0.1397)
			(layers "B.Cu" "B.Mask" "B.Paste")
			(net "P3V3_STBY")
			(options
				(clearance outline)
				(anchor circle)
			)
			(primitives
				(gr_poly
					(pts
						(arc
							(start -0.1778 0.2794)
							(mid -0.249642 0.249642)
							(end -0.2794 0.1778)
						)
						(arc
							(start -0.2794 -0.1778)
							(mid -0.249642 -0.249642)
							(end -0.1778 -0.2794)
						)
						(arc
							(start 0.1778 -0.2794)
							(mid 0.249642 -0.249642)
							(end 0.2794 -0.1778)
						)
						(arc
							(start 0.2794 0.1778)
							(mid 0.249642 0.249642)
							(end 0.1778 0.2794)
						)
					)
					(width 0)
					(fill yes)
				)
			)
		)
	)
	(footprint ""
		(layer "B.Cu")
		(at 24.461216 -170.10888 90)
		(property "Reference" "SC1114"
			(at 0 0 90)
			(layer "B.SilkS")
			(hide yes)
			(effects
				(font
					(size 1.27 1.27)
				)
				(justify mirror)
			)
		)
		(property "Value" "SCD1U16V2KX-3GP"
			(at -1.1811 -2.7051 90)
			(unlocked yes)
			(layer "B.Fab")
			(hide yes)
			(effects
				(font
					(size 1.016 1.016)
					(thickness 0.1524)
				)
				(justify mirror)
			)
		)
		(property "Device Type" "C402H22"
			(at -1.1811 -4.2291 90)
			(unlocked yes)
			(layer "B.Fab")
			(hide yes)
			(effects
				(font
					(size 1.016 1.016)
					(thickness 0.1524)
				)
				(justify mirror)
			)
		)
		(duplicate_pad_numbers_are_jumpers no)
		(fp_rect
			(start 0.4318 0.9525)
			(end -0.4318 -0.9525)
			(stroke
				(width 0)
				(type default)
			)
			(fill no)
			(layer "B.CrtYd")
		)
		(fp_rect
			(start 0.4318 0.9525)
			(end -0.4318 -0.9525)
			(stroke
				(width 0)
				(type default)
			)
			(fill no)
			(layer "B.Fab")
		)
		(pad "1" smd custom
			(at 0 -0.4445 270)
			(size 0.1524 0.1524)
			(layers "B.Cu" "B.Mask" "B.Paste")
			(net "P1V8_E")
			(options
				(clearance outline)
				(anchor circle)
			)
			(primitives
				(gr_poly
					(pts
						(arc
							(start 0.3048 0.2032)
							(mid 0.275042 0.275042)
							(end 0.2032 0.3048)
						)
						(arc
							(start -0.2032 0.3048)
							(mid -0.275042 0.275042)
							(end -0.3048 0.2032)
						)
						(arc
							(start -0.3048 -0.2032)
							(mid -0.275042 -0.275042)
							(end -0.2032 -0.3048)
						)
						(arc
							(start 0.2032 -0.3048)
							(mid 0.275042 -0.275042)
							(end 0.3048 -0.2032)
						)
					)
					(width 0)
					(fill yes)
				)
			)
		)
		(pad "2" smd custom
			(at 0 0.4445 270)
			(size 0.1524 0.1524)
			(layers "B.Cu" "B.Mask" "B.Paste")
			(net "GND")
			(options
				(clearance outline)
				(anchor circle)
			)
			(primitives
				(gr_poly
					(pts
						(arc
							(start 0.3048 0.2032)
							(mid 0.275042 0.275042)
							(end 0.2032 0.3048)
						)
						(arc
							(start -0.2032 0.3048)
							(mid -0.275042 0.275042)
							(end -0.3048 0.2032)
						)
						(arc
							(start -0.3048 -0.2032)
							(mid -0.275042 -0.275042)
							(end -0.2032 -0.3048)
						)
						(arc
							(start 0.2032 -0.3048)
							(mid 0.275042 -0.275042)
							(end 0.3048 -0.2032)
						)
					)
					(width 0)
					(fill yes)
				)
			)
		)
	)
	(footprint ""
		(layer "B.Cu")
		(at 92.818966 -55.1815 180)
		(property "Reference" "SC1009"
			(at 0 0 0)
			(layer "B.SilkS")
			(hide yes)
			(effects
				(font
					(size 1.27 1.27)
				)
				(justify mirror)
			)
		)
		(property "Value" "SC1KP50V2KX-1GP"
			(at -1.1811 -2.7051 180)
			(unlocked yes)
			(layer "B.Fab")
			(hide yes)
			(effects
				(font
					(size 1.016 1.016)
					(thickness 0.1524)
				)
				(justify mirror)
			)
		)
		(property "Device Type" "C402H22"
			(at -1.1811 -4.2291 180)
			(unlocked yes)
			(layer "B.Fab")
			(hide yes)
			(effects
				(font
					(size 1.016 1.016)
					(thickness 0.1524)
				)
				(justify mirror)
			)
		)
		(duplicate_pad_numbers_are_jumpers no)
		(fp_rect
			(start 0.4318 0.9525)
			(end -0.4318 -0.9525)
			(stroke
				(width 0)
				(type default)
			)
			(fill no)
			(layer "B.CrtYd")
		)
		(fp_rect
			(start 0.4318 0.9525)
			(end -0.4318 -0.9525)
			(stroke
				(width 0)
				(type default)
			)
			(fill no)
			(layer "B.Fab")
		)
		(pad "1" smd custom
			(at 0 -0.4445)
			(size 0.1524 0.1524)
			(layers "B.Cu" "B.Mask" "B.Paste")
			(net "P1V8_C")
			(options
				(clearance outline)
				(anchor circle)
			)
			(primitives
				(gr_poly
					(pts
						(arc
							(start 0.3048 0.2032)
							(mid 0.275042 0.275042)
							(end 0.2032 0.3048)
						)
						(arc
							(start -0.2032 0.3048)
							(mid -0.275042 0.275042)
							(end -0.3048 0.2032)
						)
						(arc
							(start -0.3048 -0.2032)
							(mid -0.275042 -0.275042)
							(end -0.2032 -0.3048)
						)
						(arc
							(start 0.2032 -0.3048)
							(mid 0.275042 -0.275042)
							(end 0.3048 -0.2032)
						)
					)
					(width 0)
					(fill yes)
				)
			)
		)
		(pad "2" smd custom
			(at 0 0.4445)
			(size 0.1524 0.1524)
			(layers "B.Cu" "B.Mask" "B.Paste")
			(net "GND")
			(options
				(clearance outline)
				(anchor circle)
			)
			(primitives
				(gr_poly
					(pts
						(arc
							(start 0.3048 0.2032)
							(mid 0.275042 0.275042)
							(end 0.2032 0.3048)
						)
						(arc
							(start -0.2032 0.3048)
							(mid -0.275042 0.275042)
							(end -0.3048 0.2032)
						)
						(arc
							(start -0.3048 -0.2032)
							(mid -0.275042 -0.275042)
							(end -0.2032 -0.3048)
						)
						(arc
							(start 0.2032 -0.3048)
							(mid 0.275042 -0.275042)
							(end 0.3048 -0.2032)
						)
					)
					(width 0)
					(fill yes)
				)
			)
		)
	)
	(footprint ""
		(layer "B.Cu")
		(at 88.91016 -50.419)
		(property "Reference" "STP14"
			(at 0 0 0)
			(layer "B.SilkS")
			(hide yes)
			(effects
				(font
					(size 1.27 1.27)
				)
				(justify mirror)
			)
		)
		(property "Value" "TPAD28"
			(at -0.0127 -1.8034 0)
			(unlocked yes)
			(layer "B.Fab")
			(hide yes)
			(effects
				(font
					(size 1.016 1.016)
					(thickness 0.1524)
				)
				(justify mirror)
			)
		)
		(property "Device Type" "TPAD28"
			(at -0.0127 -3.3274 0)
			(unlocked yes)
			(layer "B.Fab")
			(hide yes)
			(effects
				(font
					(size 1.016 1.016)
					(thickness 0.1524)
				)
				(justify mirror)
			)
		)
		(duplicate_pad_numbers_are_jumpers no)
		(fp_poly
			(pts
				(arc
					(start 0.3556 0)
					(mid -0.3556 0)
					(end 0.3556 0)
				)
			)
			(stroke
				(width 0)
				(type default)
			)
			(fill no)
			(layer "B.CrtYd")
		)
		(fp_poly
			(pts
				(arc
					(start 0.6096 0)
					(mid -0.6096 0)
					(end 0.6096 0)
				)
			)
			(stroke
				(width 0)
				(type default)
			)
			(fill no)
			(layer "B.Fab")
		)
		(pad "1" smd circle
			(at 0 0 180)
			(size 0.7112 0.7112)
			(layers "B.Cu" "B.Mask" "B.Paste")
			(net "SIO_DIN_1")
		)
	)
	(footprint ""
		(layer "B.Cu")
		(at 188.949584 -104.299766)
		(property "Reference" ""
			(at 0 0 0)
			(layer "B.SilkS")
			(hide yes)
			(effects
				(font
					(size 1.27 1.27)
				)
				(justify mirror)
			)
		)
		(property "Value" "*"
			(at 5.5753 -0.4572 0)
			(unlocked yes)
			(layer "B.Fab")
			(hide yes)
			(effects
				(font
					(size 1.016 1.016)
					(thickness 0.1524)
				)
				(justify mirror)
			)
		)
		(duplicate_pad_numbers_are_jumpers no)
		(fp_poly
			(pts
				(arc
					(start 4.3053 0)
					(mid -4.3053 0)
					(end 4.3053 0)
				)
			)
			(stroke
				(width 0)
				(type default)
			)
			(fill no)
			(layer "B.CrtYd")
		)
		(fp_poly
			(pts
				(arc
					(start 4.3053 0)
					(mid -4.3053 0)
					(end 4.3053 0)
				)
			)
			(stroke
				(width 0)
				(type default)
			)
			(fill no)
			(layer "B.Fab")
		)
		(pad "1" smd custom
			(at 2.95275 0 180)
			(size 2.000013 2.000013)
			(layers "B.Cu" "B.Mask" "B.Paste")
			(net "Net_51")
			(options
				(clearance outline)
				(anchor circle)
			)
			(primitives
				(gr_poly
					(pts
						(arc
							(start 4.0005 -0.00254)
							(mid -4.000501 0)
							(end 4.0005 0.00254)
						)
						(arc
							(start 1.905 0.00254)
							(mid -1.905002 0)
							(end 1.905 -0.00254)
						)
					)
					(width 0)
					(fill yes)
				)
			)
		)
	)
	(footprint ""
		(layer "B.Cu")
		(at 97.898966 -56.261 180)
		(property "Reference" "SC971"
			(at 0 0 0)
			(layer "B.SilkS")
			(hide yes)
			(effects
				(font
					(size 1.27 1.27)
				)
				(justify mirror)
			)
		)
		(property "Value" "SC1U10V2KX-4-GP"
			(at -1.1811 -2.7051 180)
			(unlocked yes)
			(layer "B.Fab")
			(hide yes)
			(effects
				(font
					(size 1.016 1.016)
					(thickness 0.1524)
				)
				(justify mirror)
			)
		)
		(property "Device Type" "C402H22"
			(at -1.1811 -4.2291 180)
			(unlocked yes)
			(layer "B.Fab")
			(hide yes)
			(effects
				(font
					(size 1.016 1.016)
					(thickness 0.1524)
				)
				(justify mirror)
			)
		)
		(duplicate_pad_numbers_are_jumpers no)
		(fp_rect
			(start 0.4318 0.9525)
			(end -0.4318 -0.9525)
			(stroke
				(width 0)
				(type default)
			)
			(fill no)
			(layer "B.CrtYd")
		)
		(fp_rect
			(start 0.4318 0.9525)
			(end -0.4318 -0.9525)
			(stroke
				(width 0)
				(type default)
			)
			(fill no)
			(layer "B.Fab")
		)
		(pad "1" smd custom
			(at 0 -0.4445)
			(size 0.1524 0.1524)
			(layers "B.Cu" "B.Mask" "B.Paste")
			(net "P1V8_C")
			(options
				(clearance outline)
				(anchor circle)
			)
			(primitives
				(gr_poly
					(pts
						(arc
							(start 0.3048 0.2032)
							(mid 0.275042 0.275042)
							(end 0.2032 0.3048)
						)
						(arc
							(start -0.2032 0.3048)
							(mid -0.275042 0.275042)
							(end -0.3048 0.2032)
						)
						(arc
							(start -0.3048 -0.2032)
							(mid -0.275042 -0.275042)
							(end -0.2032 -0.3048)
						)
						(arc
							(start 0.2032 -0.3048)
							(mid 0.275042 -0.275042)
							(end 0.3048 -0.2032)
						)
					)
					(width 0)
					(fill yes)
				)
			)
		)
		(pad "2" smd custom
			(at 0 0.4445)
			(size 0.1524 0.1524)
			(layers "B.Cu" "B.Mask" "B.Paste")
			(net "GND")
			(options
				(clearance outline)
				(anchor circle)
			)
			(primitives
				(gr_poly
					(pts
						(arc
							(start 0.3048 0.2032)
							(mid 0.275042 0.275042)
							(end 0.2032 0.3048)
						)
						(arc
							(start -0.2032 0.3048)
							(mid -0.275042 0.275042)
							(end -0.3048 0.2032)
						)
						(arc
							(start -0.3048 -0.2032)
							(mid -0.275042 -0.275042)
							(end -0.2032 -0.3048)
						)
						(arc
							(start 0.2032 -0.3048)
							(mid 0.275042 -0.275042)
							(end 0.3048 -0.2032)
						)
					)
					(width 0)
					(fill yes)
				)
			)
		)
	)
)
